(kicad_pcb
	(version 20260206)
	(generator "pcbnew")
	(generator_version "10.0")
	(general
		(thickness 1.6)
		(legacy_teardrops no)
	)
	(paper "A4")
	(title_block
		(title "9052_F0T_PDB_Converter_Brick_F_V03_1208_1600_OCP.brd")
		(comment 1 "Grand Teton / footprints 119-123 of 578")
	)
	(layers
		(0 "F.Cu" signal "TOP")
		(4 "In1.Cu" signal "GND")
		(6 "In2.Cu" signal "IN1")
		(8 "In3.Cu" signal "GND1")
		(10 "In4.Cu" signal "VCC")
		(12 "In5.Cu" signal "VCC1")
		(14 "In6.Cu" signal "GND2")
		(16 "In7.Cu" signal "IN2")
		(18 "In8.Cu" signal "GND3")
		(2 "B.Cu" signal "BOTTOM")
		(9 "F.Adhes" user "F.Adhesive")
		(11 "B.Adhes" user "B.Adhesive")
		(13 "F.Paste" user "Package Geometry/Pastemask Top")
		(15 "B.Paste" user "Package Geometry/Pastemask Bottom")
		(5 "F.SilkS" user "Ref Des/Silkscreen Top")
		(7 "B.SilkS" user "Ref Des/Silkscreen Bottom")
		(1 "F.Mask" user "Board Geometry/Soldermask Top")
		(3 "B.Mask" user "Board Geometry/Soldermask Bottom")
		(17 "Dwgs.User" user "User.Drawings")
		(19 "Cmts.User" user "User.Comments")
		(21 "Eco1.User" user "User.Eco1")
		(23 "Eco2.User" user "User.Eco2")
		(25 "Edge.Cuts" user "Board Geometry/Outline")
		(27 "Margin" user)
		(31 "F.CrtYd" user "Package Geometry/Place Bound Top")
		(29 "B.CrtYd" user "Package Geometry/Place Bound Bottom")
		(35 "F.Fab" user "Ref Des/Assembly Top")
		(33 "B.Fab" user "Ref Des/Assembly Bottom")
	)
	(footprint ""
		(layer "F.Cu")
		(at 278.1554 -24.257 90)
		(property "Reference" "C90"
			(at 0 0 90)
			(layer "F.SilkS")
			(hide yes)
			(effects
				(font
					(size 1.27 1.27)
				)
			)
		)
		(property "Value" ""
			(at 0 0 90)
			(layer "F.Fab")
			(effects
				(font
					(size 1.27 1.27)
				)
			)
		)
		(duplicate_pad_numbers_are_jumpers no)
		(fp_line
			(start 0.7874 -0.4064)
			(end 0.7874 0.4064)
			(stroke
				(width 0.1524)
				(type default)
			)
			(layer "F.SilkS")
		)
		(fp_line
			(start -0.7874 -0.4064)
			(end 0.7874 -0.4064)
			(stroke
				(width 0.1524)
				(type default)
			)
			(layer "F.SilkS")
		)
		(fp_line
			(start 0.7874 0.4064)
			(end -0.7874 0.4064)
			(stroke
				(width 0.1524)
				(type default)
			)
			(layer "F.SilkS")
		)
		(fp_line
			(start -0.7874 0.4064)
			(end -0.7874 -0.4064)
			(stroke
				(width 0.1524)
				(type default)
			)
			(layer "F.SilkS")
		)
		(fp_line
			(start -0.12065 -0.305054)
			(end -0.12065 -0.2794)
			(stroke
				(width 0.1)
				(type default)
			)
			(layer "F.Fab")
		)
		(fp_line
			(start -0.67945 -0.305054)
			(end -0.12065 -0.305054)
			(stroke
				(width 0.1)
				(type default)
			)
			(layer "F.Fab")
		)
		(fp_line
			(start 0.67945 -0.3048)
			(end 0.67945 0.3048)
			(stroke
				(width 0.1)
				(type default)
			)
			(layer "F.Fab")
		)
		(fp_line
			(start 0.12065 -0.3048)
			(end 0.67945 -0.3048)
			(stroke
				(width 0.1)
				(type default)
			)
			(layer "F.Fab")
		)
		(fp_line
			(start 0.12065 -0.2794)
			(end 0.12065 -0.3048)
			(stroke
				(width 0.1)
				(type default)
			)
			(layer "F.Fab")
		)
		(fp_line
			(start -0.12065 -0.2794)
			(end 0.12065 -0.2794)
			(stroke
				(width 0.1)
				(type default)
			)
			(layer "F.Fab")
		)
		(fp_line
			(start 0.120396 0.2794)
			(end -0.12065 0.2794)
			(stroke
				(width 0.1)
				(type default)
			)
			(layer "F.Fab")
		)
		(fp_line
			(start -0.12065 0.2794)
			(end -0.12065 0.3048)
			(stroke
				(width 0.1)
				(type default)
			)
			(layer "F.Fab")
		)
		(fp_line
			(start 0.67945 0.3048)
			(end 0.120396 0.3048)
			(stroke
				(width 0.1)
				(type default)
			)
			(layer "F.Fab")
		)
		(fp_line
			(start 0.120396 0.3048)
			(end 0.120396 0.2794)
			(stroke
				(width 0.1)
				(type default)
			)
			(layer "F.Fab")
		)
		(fp_line
			(start -0.12065 0.3048)
			(end -0.67945 0.3048)
			(stroke
				(width 0.1)
				(type default)
			)
			(layer "F.Fab")
		)
		(fp_line
			(start -0.67945 0.3048)
			(end -0.67945 -0.305054)
			(stroke
				(width 0.1)
				(type default)
			)
			(layer "F.Fab")
		)
		(pad "1" smd circle
			(at -0.40005 0 90)
			(size 0 0)
			(layers "F.Cu" "F.Mask" "F.Paste")
			(net "P3V3_AND")
		)
		(pad "2" smd circle
			(at 0.40005 0 90)
			(size 0 0)
			(layers "F.Cu" "F.Mask" "F.Paste")
			(net "GND")
		)
	)
	(footprint ""
		(layer "F.Cu")
		(at 282.575 -35.687 -90)
		(property "Reference" "R151"
			(at 0 0 270)
			(layer "F.SilkS")
			(hide yes)
			(effects
				(font
					(size 1.27 1.27)
				)
			)
		)
		(property "Value" ""
			(at 0 0 270)
			(layer "F.Fab")
			(effects
				(font
					(size 1.27 1.27)
				)
			)
		)
		(duplicate_pad_numbers_are_jumpers no)
		(fp_line
			(start -0.7874 0.4064)
			(end -0.7874 -0.4064)
			(stroke
				(width 0.1524)
				(type default)
			)
			(layer "F.SilkS")
		)
		(fp_line
			(start 0.7874 0.4064)
			(end -0.7874 0.4064)
			(stroke
				(width 0.1524)
				(type default)
			)
			(layer "F.SilkS")
		)
		(fp_line
			(start -0.7874 -0.4064)
			(end 0.7874 -0.4064)
			(stroke
				(width 0.1524)
				(type default)
			)
			(layer "F.SilkS")
		)
		(fp_line
			(start 0.7874 -0.4064)
			(end 0.7874 0.4064)
			(stroke
				(width 0.1524)
				(type default)
			)
			(layer "F.SilkS")
		)
		(fp_line
			(start -0.67945 0.3048)
			(end -0.67945 -0.305054)
			(stroke
				(width 0.1)
				(type default)
			)
			(layer "F.Fab")
		)
		(fp_line
			(start -0.12065 0.3048)
			(end -0.67945 0.3048)
			(stroke
				(width 0.1)
				(type default)
			)
			(layer "F.Fab")
		)
		(fp_line
			(start 0.120396 0.3048)
			(end 0.120396 0.2794)
			(stroke
				(width 0.1)
				(type default)
			)
			(layer "F.Fab")
		)
		(fp_line
			(start 0.67945 0.3048)
			(end 0.120396 0.3048)
			(stroke
				(width 0.1)
				(type default)
			)
			(layer "F.Fab")
		)
		(fp_line
			(start -0.12065 0.2794)
			(end -0.12065 0.3048)
			(stroke
				(width 0.1)
				(type default)
			)
			(layer "F.Fab")
		)
		(fp_line
			(start 0.120396 0.2794)
			(end -0.12065 0.2794)
			(stroke
				(width 0.1)
				(type default)
			)
			(layer "F.Fab")
		)
		(fp_line
			(start -0.12065 -0.2794)
			(end 0.12065 -0.2794)
			(stroke
				(width 0.1)
				(type default)
			)
			(layer "F.Fab")
		)
		(fp_line
			(start 0.12065 -0.2794)
			(end 0.12065 -0.3048)
			(stroke
				(width 0.1)
				(type default)
			)
			(layer "F.Fab")
		)
		(fp_line
			(start 0.12065 -0.3048)
			(end 0.67945 -0.3048)
			(stroke
				(width 0.1)
				(type default)
			)
			(layer "F.Fab")
		)
		(fp_line
			(start 0.67945 -0.3048)
			(end 0.67945 0.3048)
			(stroke
				(width 0.1)
				(type default)
			)
			(layer "F.Fab")
		)
		(fp_line
			(start -0.67945 -0.305054)
			(end -0.12065 -0.305054)
			(stroke
				(width 0.1)
				(type default)
			)
			(layer "F.Fab")
		)
		(fp_line
			(start -0.12065 -0.305054)
			(end -0.12065 -0.2794)
			(stroke
				(width 0.1)
				(type default)
			)
			(layer "F.Fab")
		)
		(pad "1" smd circle
			(at -0.40005 0 270)
			(size 0 0)
			(layers "F.Cu" "F.Mask" "F.Paste")
			(net "P52V_HS1_GPO2")
		)
		(pad "2" smd circle
			(at 0.40005 0 270)
			(size 0 0)
			(layers "F.Cu" "F.Mask" "F.Paste")
			(net "P52V_HS1_FLT")
		)
	)
	(footprint ""
		(layer "F.Cu")
		(at 64.470026 -121.209816)
		(property "Reference" "PU4"
			(at -26.563066 -5.12953 0)
			(unlocked yes)
			(layer "F.SilkS")
			(effects
				(font
					(size 0.7874 0.5842)
					(thickness 0.1524)
				)
				(justify left)
			)
		)
		(property "Value" ""
			(at 0 0 0)
			(layer "F.Fab")
			(effects
				(font
					(size 1.27 1.27)
				)
			)
		)
		(duplicate_pad_numbers_are_jumpers no)
		(fp_line
			(start -26.519886 -4.299966)
			(end -26.519886 55.099966)
			(stroke
				(width 0.1524)
				(type default)
			)
			(layer "F.SilkS")
		)
		(fp_line
			(start -26.519886 55.099966)
			(end 11.279886 55.099966)
			(stroke
				(width 0.1524)
				(type default)
			)
			(layer "F.SilkS")
		)
		(fp_line
			(start -26.020014 -3.800094)
			(end -26.020014 54.59984)
			(stroke
				(width 0.1524)
				(type default)
			)
			(layer "F.SilkS")
		)
		(fp_line
			(start -26.020014 54.59984)
			(end 10.780014 54.59984)
			(stroke
				(width 0.1524)
				(type default)
			)
			(layer "F.SilkS")
		)
		(fp_line
			(start 10.780014 -3.800094)
			(end -26.020014 -3.800094)
			(stroke
				(width 0.1524)
				(type default)
			)
			(layer "F.SilkS")
		)
		(fp_line
			(start 10.780014 54.59984)
			(end 10.780014 -3.800094)
			(stroke
				(width 0.1524)
				(type default)
			)
			(layer "F.SilkS")
		)
		(fp_line
			(start 11.279886 -4.299966)
			(end -26.519886 -4.299966)
			(stroke
				(width 0.1524)
				(type default)
			)
			(layer "F.SilkS")
		)
		(fp_line
			(start 11.279886 55.099966)
			(end 11.279886 -4.299966)
			(stroke
				(width 0.1524)
				(type default)
			)
			(layer "F.SilkS")
		)
		(fp_poly
			(pts
				(xy 1.27 -7.44728) (xy -1.27 -7.44728) (xy 0 -4.90728)
			)
			(stroke
				(width 0)
				(type default)
			)
			(fill yes)
			(layer "F.SilkS")
		)
		(fp_line
			(start -26.020014 -3.800094)
			(end -26.020014 54.59984)
			(stroke
				(width 0.1)
				(type default)
			)
			(layer "F.Fab")
		)
		(fp_line
			(start -26.020014 54.59984)
			(end 10.780014 54.59984)
			(stroke
				(width 0.1)
				(type default)
			)
			(layer "F.Fab")
		)
		(fp_line
			(start 10.780014 -3.800094)
			(end -26.020014 -3.800094)
			(stroke
				(width 0.1)
				(type default)
			)
			(layer "F.Fab")
		)
		(fp_line
			(start 10.780014 54.59984)
			(end 10.780014 -3.800094)
			(stroke
				(width 0.1)
				(type default)
			)
			(layer "F.Fab")
		)
		(fp_poly
			(pts
				(xy 1.27 -7.44728) (xy -1.27 -7.44728) (xy 0 -4.90728)
			)
			(stroke
				(width 0)
				(type default)
			)
			(fill yes)
			(layer "F.Fab")
		)
		(pad "1" thru_hole rect
			(at 0 0 270)
			(size 2.3622 2.3622)
			(drill 1.6002)
			(layers "*.Cu" "*.Mask")
			(remove_unused_layers no)
			(net "P52V_HS_FILTER")
			(clearance -0.127)
			(padstack
				(mode front_inner_back)
				(layer "Inner"
					(shape circle)
					(size 2.3622 2.3622)
					(clearance -0.127)
				)
				(layer "B.Cu"
					(shape rect)
					(size 2.3622 2.3622)
					(clearance -0.127)
				)
			)
		)
		(pad "2" thru_hole circle
			(at -7.62 0 270)
			(size 2.3622 2.3622)
			(drill 1.6002)
			(layers "*.Cu" "*.Mask")
			(remove_unused_layers no)
			(net "BRICK_P12V3_ON_OFF_R")
			(clearance -0.127)
		)
		(pad "3" thru_hole circle
			(at -15.24 0 270)
			(size 2.3622 2.3622)
			(drill 1.6002)
			(layers "*.Cu" "*.Mask")
			(remove_unused_layers no)
			(net "GND")
			(clearance -0.127)
		)
		(pad "4" thru_hole circle
			(at -19.05 50.8 270)
			(size 3.1242 3.1242)
			(drill 2.1082)
			(layers "*.Cu" "*.Mask")
			(remove_unused_layers no)
			(net "GND")
			(clearance -0.254)
		)
		(pad "5" thru_hole circle
			(at -15.24 50.8 270)
			(size 3.1242 3.1242)
			(drill 2.1082)
			(layers "*.Cu" "*.Mask")
			(remove_unused_layers no)
			(net "GND")
			(clearance -0.254)
		)
		(pad "6" thru_hole circle
			(at 0 50.8 270)
			(size 3.1242 3.1242)
			(drill 2.1082)
			(layers "*.Cu" "*.Mask")
			(remove_unused_layers no)
			(net "P12V_BRICK")
			(clearance -0.254)
		)
		(pad "7" thru_hole circle
			(at 3.81 50.8 270)
			(size 3.1242 3.1242)
			(drill 2.1082)
			(layers "*.Cu" "*.Mask")
			(remove_unused_layers no)
			(net "P12V_BRICK")
			(clearance -0.254)
		)
		(pad "8" thru_hole circle
			(at -13.619988 53.34 270)
			(size 1.3208 1.3208)
			(drill 0.9144)
			(layers "*.Cu" "*.Mask")
			(remove_unused_layers no)
			(net "P12V_BRICK_PWRGD")
			(clearance 0.0508)
			(thermal_gap 0.0508)
		)
		(pad "9" thru_hole circle
			(at -11.619992 53.34 270)
			(size 1.3208 1.3208)
			(drill 0.9144)
			(layers "*.Cu" "*.Mask")
			(remove_unused_layers no)
			(net "P12V_MB3_SENSE-")
			(clearance 0.0508)
			(thermal_gap 0.0508)
		)
		(pad "10" thru_hole circle
			(at -9.619996 53.34 270)
			(size 1.3208 1.3208)
			(drill 0.9144)
			(layers "*.Cu" "*.Mask")
			(remove_unused_layers no)
			(net "SMB_BRICK3_SDA")
			(clearance 0.0508)
			(thermal_gap 0.0508)
		)
		(pad "11" thru_hole circle
			(at -7.62 53.34 270)
			(size 1.3208 1.3208)
			(drill 0.9144)
			(layers "*.Cu" "*.Mask")
			(remove_unused_layers no)
			(net "SMB_BRICK3_ALERT")
			(clearance 0.0508)
			(thermal_gap 0.0508)
		)
		(pad "12" thru_hole circle
			(at -5.620004 53.34 270)
			(size 1.3208 1.3208)
			(drill 0.9144)
			(layers "*.Cu" "*.Mask")
			(remove_unused_layers no)
			(net "SMB_BRICK3_SCL")
			(clearance 0.0508)
			(thermal_gap 0.0508)
		)
		(pad "13" thru_hole circle
			(at -3.620008 53.34 270)
			(size 1.3208 1.3208)
			(drill 0.9144)
			(layers "*.Cu" "*.Mask")
			(remove_unused_layers no)
			(net "BRICK3_PMBADD")
			(clearance 0.0508)
			(thermal_gap 0.0508)
		)
		(pad "14" thru_hole circle
			(at -1.620012 53.34 270)
			(size 1.3208 1.3208)
			(drill 0.9144)
			(layers "*.Cu" "*.Mask")
			(remove_unused_layers no)
			(net "P12V_MB3_SENSE+")
			(clearance 0.0508)
			(thermal_gap 0.0508)
		)
	)
	(footprint ""
		(layer "F.Cu")
		(at 79.121 -51.943)
		(property "Reference" "PC92"
			(at 0 0 0)
			(layer "F.SilkS")
			(hide yes)
			(effects
				(font
					(size 1.27 1.27)
				)
			)
		)
		(property "Value" ""
			(at 0 0 0)
			(layer "F.Fab")
			(effects
				(font
					(size 1.27 1.27)
				)
			)
		)
		(duplicate_pad_numbers_are_jumpers no)
		(fp_line
			(start -1.524 -0.762)
			(end 1.524 -0.762)
			(stroke
				(width 0.1524)
				(type default)
			)
			(layer "F.SilkS")
		)
		(fp_line
			(start -1.524 0.762)
			(end -1.524 -0.762)
			(stroke
				(width 0.1524)
				(type default)
			)
			(layer "F.SilkS")
		)
		(fp_line
			(start 1.524 -0.762)
			(end 1.524 0.762)
			(stroke
				(width 0.1524)
				(type default)
			)
			(layer "F.SilkS")
		)
		(fp_line
			(start 1.524 0.762)
			(end -1.524 0.762)
			(stroke
				(width 0.1524)
				(type default)
			)
			(layer "F.SilkS")
		)
		(fp_line
			(start -1.1049 -0.724916)
			(end -1.1049 0.724916)
			(stroke
				(width 0.1)
				(type default)
			)
			(layer "F.Fab")
		)
		(fp_line
			(start -1.1049 0.724916)
			(end 1.1049 0.724916)
			(stroke
				(width 0.1)
				(type default)
			)
			(layer "F.Fab")
		)
		(fp_line
			(start 1.1049 -0.724916)
			(end -1.1049 -0.724916)
			(stroke
				(width 0.1)
				(type default)
			)
			(layer "F.Fab")
		)
		(fp_line
			(start 1.1049 0.724916)
			(end 1.1049 -0.724916)
			(stroke
				(width 0.1)
				(type default)
			)
			(layer "F.Fab")
		)
		(pad "1" smd rect
			(at -0.889 0 180)
			(size 1.016 1.27)
			(layers "F.Cu" "F.Mask" "F.Paste")
			(net "P12V_BRICK")
		)
		(pad "2" smd rect
			(at 0.889 0 180)
			(size 1.016 1.27)
			(layers "F.Cu" "F.Mask" "F.Paste")
			(net "GND")
		)
	)
	(footprint ""
		(layer "F.Cu")
		(at 301.602394 -83.5025)
		(property "Reference" "PR6961"
			(at 0 0 0)
			(layer "F.SilkS")
			(hide yes)
			(effects
				(font
					(size 1.27 1.27)
				)
			)
		)
		(property "Value" ""
			(at 0 0 0)
			(layer "F.Fab")
			(effects
				(font
					(size 1.27 1.27)
				)
			)
		)
		(duplicate_pad_numbers_are_jumpers no)
		(fp_line
			(start -1.2954 -0.5842)
			(end 1.2954 -0.5842)
			(stroke
				(width 0.1524)
				(type default)
			)
			(layer "F.SilkS")
		)
		(fp_line
			(start -1.2954 0.5842)
			(end -1.2954 -0.5842)
			(stroke
				(width 0.1524)
				(type default)
			)
			(layer "F.SilkS")
		)
		(fp_line
			(start 1.2954 -0.5842)
			(end 1.2954 0.5842)
			(stroke
				(width 0.1524)
				(type default)
			)
			(layer "F.SilkS")
		)
		(fp_line
			(start 1.2954 0.5842)
			(end -1.2954 0.5842)
			(stroke
				(width 0.1524)
				(type default)
			)
			(layer "F.SilkS")
		)
		(fp_line
			(start -1.1938 -0.406654)
			(end -0.8636 -0.406654)
			(stroke
				(width 0.1)
				(type default)
			)
			(layer "F.Fab")
		)
		(fp_line
			(start -1.1938 0.4064)
			(end -1.1938 -0.406654)
			(stroke
				(width 0.1)
				(type default)
			)
			(layer "F.Fab")
		)
		(fp_line
			(start -0.8636 -0.4572)
			(end 0.8636 -0.4572)
			(stroke
				(width 0.1)
				(type default)
			)
			(layer "F.Fab")
		)
		(fp_line
			(start -0.8636 -0.406654)
			(end -0.8636 -0.4572)
			(stroke
				(width 0.1)
				(type default)
			)
			(layer "F.Fab")
		)
		(fp_line
			(start -0.8636 0.4064)
			(end -1.1938 0.4064)
			(stroke
				(width 0.1)
				(type default)
			)
			(layer "F.Fab")
		)
		(fp_line
			(start -0.8636 0.4318)
			(end -0.8636 0.4064)
			(stroke
				(width 0.1)
				(type default)
			)
			(layer "F.Fab")
		)
		(fp_line
			(start -0.8636 0.4572)
			(end -0.8636 0.4318)
			(stroke
				(width 0.1)
				(type default)
			)
			(layer "F.Fab")
		)
		(fp_line
			(start 0.8636 -0.4572)
			(end 0.8636 -0.406654)
			(stroke
				(width 0.1)
				(type default)
			)
			(layer "F.Fab")
		)
		(fp_line
			(start 0.8636 -0.406654)
			(end 1.1938 -0.406654)
			(stroke
				(width 0.1)
				(type default)
			)
			(layer "F.Fab")
		)
		(fp_line
			(start 0.8636 0.4064)
			(end 0.8636 0.4572)
			(stroke
				(width 0.1)
				(type default)
			)
			(layer "F.Fab")
		)
		(fp_line
			(start 0.8636 0.4572)
			(end -0.8636 0.4572)
			(stroke
				(width 0.1)
				(type default)
			)
			(layer "F.Fab")
		)
		(fp_line
			(start 1.1938 -0.406654)
			(end 1.1938 0.4064)
			(stroke
				(width 0.1)
				(type default)
			)
			(layer "F.Fab")
		)
		(fp_line
			(start 1.1938 0.4064)
			(end 0.8636 0.4064)
			(stroke
				(width 0.1)
				(type default)
			)
			(layer "F.Fab")
		)
		(pad "1" smd rect
			(at -0.7366 0 270)
			(size 0.7112 0.8128)
			(layers "F.Cu" "F.Mask" "F.Paste")
			(net "P52V_HS_1272_S_P")
		)
		(pad "2" smd rect
			(at 0.7366 0 270)
			(size 0.7112 0.8128)
			(layers "F.Cu" "F.Mask" "F.Paste")
			(net "P52V_HS1_SENSE_P_R2")
		)
	)
)
